# T6G (Grand Teton) — schematic netlist excerpt (pin names and nets, part order shuffled) for the footprints in the layout excerpt that follows; sources: Cadence DE-HDL packaged netlist, KiCad conversion of 04192023_DAF0TMB3IC0_F0TG_MB_C_brd_V02_OCP.brd

C608  Q_CAP  0.1UF 10V 10% X7S  pkg C0201  page 290 : A = P0V9_CPU0_RT_2D ; B = GND
C2582  Q_CAP  22UF 4V 20% X6S  pkg C0402  page 70 : A = PVDDCR_SOC_P0 ; B = GND
R385  Q_RES  15 1% CHIP  pkg 0402LF  page 20 : A = M_K_CPU0_ALERT_N ; B = M_K_CPU0_ALERT_R_N

(kicad_pcb
	(version 20260206)
	(generator "pcbnew")
	(generator_version "10.0")
	(general
		(thickness 1.6)
		(legacy_teardrops no)
	)
	(paper "A4")
	(title_block
		(title "04192023_DAF0TMB3IC0_F0TG_MB_C_brd_V02_OCP.brd")
		(comment 1 "Grand Teton / footprints 5738-5740 of 8354")
	)
	(layers
		(0 "F.Cu" signal "TOP")
		(4 "In1.Cu" signal "GND")
		(6 "In2.Cu" signal "IN1")
		(8 "In3.Cu" signal "GND1")
		(10 "In4.Cu" signal "IN2")
		(12 "In5.Cu" signal "GND2")
		(14 "In6.Cu" signal "IN3")
		(16 "In7.Cu" signal "GND3")
		(18 "In8.Cu" signal "VCC")
		(20 "In9.Cu" signal "VCC1")
		(22 "In10.Cu" signal "GND4")
		(24 "In11.Cu" signal "IN4")
		(26 "In12.Cu" signal "GND5")
		(28 "In13.Cu" signal "IN5")
		(30 "In14.Cu" signal "GND6")
		(32 "In15.Cu" signal "IN6")
		(34 "In16.Cu" signal "GND7")
		(2 "B.Cu" signal "BOTTOM")
		(9 "F.Adhes" user "F.Adhesive")
		(11 "B.Adhes" user "B.Adhesive")
		(13 "F.Paste" user "Package Geometry/Pastemask Top")
		(15 "B.Paste" user "Package Geometry/Pastemask Bottom")
		(5 "F.SilkS" user "Ref Des/Silkscreen Top")
		(7 "B.SilkS" user "Ref Des/Silkscreen Bottom")
		(1 "F.Mask" user "Board Geometry/Soldermask Top")
		(3 "B.Mask" user "Board Geometry/Soldermask Bottom")
		(17 "Dwgs.User" user "User.Drawings")
		(19 "Cmts.User" user "User.Comments")
		(21 "Eco1.User" user "User.Eco1")
		(23 "Eco2.User" user "User.Eco2")
		(25 "Edge.Cuts" user "Board Geometry/Outline")
		(27 "Margin" user)
		(31 "F.CrtYd" user "Package Geometry/Place Bound Top")
		(29 "B.CrtYd" user "Package Geometry/Place Bound Bottom")
		(35 "F.Fab" user "Ref Des/Assembly Top")
		(33 "B.Fab" user "Ref Des/Assembly Bottom")
	)
	(footprint ""
		(layer "B.Cu")
		(at 445.647318 -244.08511)
		(property "Reference" "R385"
			(at 0 0 0)
			(layer "B.SilkS")
			(hide yes)
			(effects
				(font
					(size 1.27 1.27)
				)
				(justify mirror)
			)
		)
		(property "Value" ""
			(at 0 0 0)
			(layer "B.Fab")
			(effects
				(font
					(size 1.27 1.27)
				)
				(justify mirror)
			)
		)
		(duplicate_pad_numbers_are_jumpers no)
		(fp_line
			(start -0.7874 -0.4064)
			(end -0.7874 0.4064)
			(stroke
				(width 0.1524)
				(type default)
			)
			(layer "B.SilkS")
		)
		(fp_line
			(start -0.7874 0.4064)
			(end 0.7874 0.4064)
			(stroke
				(width 0.1524)
				(type default)
			)
			(layer "B.SilkS")
		)
		(fp_line
			(start 0.7874 -0.4064)
			(end -0.7874 -0.4064)
			(stroke
				(width 0.1524)
				(type default)
			)
			(layer "B.SilkS")
		)
		(fp_line
			(start 0.7874 0.4064)
			(end 0.7874 -0.4064)
			(stroke
				(width 0.1524)
				(type default)
			)
			(layer "B.SilkS")
		)
		(fp_line
			(start -0.67945 -0.3048)
			(end -0.67945 0.3048)
			(stroke
				(width 0.1)
				(type default)
			)
			(layer "B.Fab")
		)
		(fp_line
			(start -0.67945 0.3048)
			(end -0.120396 0.3048)
			(stroke
				(width 0.1)
				(type default)
			)
			(layer "B.Fab")
		)
		(fp_line
			(start -0.12065 -0.3048)
			(end -0.67945 -0.3048)
			(stroke
				(width 0.1)
				(type default)
			)
			(layer "B.Fab")
		)
		(fp_line
			(start -0.12065 -0.2794)
			(end -0.12065 -0.3048)
			(stroke
				(width 0.1)
				(type default)
			)
			(layer "B.Fab")
		)
		(fp_line
			(start -0.120396 0.2794)
			(end 0.12065 0.2794)
			(stroke
				(width 0.1)
				(type default)
			)
			(layer "B.Fab")
		)
		(fp_line
			(start -0.120396 0.3048)
			(end -0.120396 0.2794)
			(stroke
				(width 0.1)
				(type default)
			)
			(layer "B.Fab")
		)
		(fp_line
			(start 0.12065 -0.305054)
			(end 0.12065 -0.2794)
			(stroke
				(width 0.1)
				(type default)
			)
			(layer "B.Fab")
		)
		(fp_line
			(start 0.12065 -0.2794)
			(end -0.12065 -0.2794)
			(stroke
				(width 0.1)
				(type default)
			)
			(layer "B.Fab")
		)
		(fp_line
			(start 0.12065 0.2794)
			(end 0.12065 0.3048)
			(stroke
				(width 0.1)
				(type default)
			)
			(layer "B.Fab")
		)
		(fp_line
			(start 0.12065 0.3048)
			(end 0.67945 0.3048)
			(stroke
				(width 0.1)
				(type default)
			)
			(layer "B.Fab")
		)
		(fp_line
			(start 0.67945 -0.305054)
			(end 0.12065 -0.305054)
			(stroke
				(width 0.1)
				(type default)
			)
			(layer "B.Fab")
		)
		(fp_line
			(start 0.67945 0.3048)
			(end 0.67945 -0.305054)
			(stroke
				(width 0.1)
				(type default)
			)
			(layer "B.Fab")
		)
		(pad "1" smd circle
			(at 0.40005 0 180)
			(size 0 0)
			(layers "B.Cu" "B.Mask" "B.Paste")
			(net "M_K_CPU0_ALERT_N")
		)
		(pad "2" smd circle
			(at -0.40005 0 180)
			(size 0 0)
			(layers "B.Cu" "B.Mask" "B.Paste")
			(net "M_K_CPU0_ALERT_R_N")
		)
	)
	(footprint ""
		(layer "B.Cu")
		(at 342.046052 -396.393162 -90)
		(property "Reference" "C608"
			(at 0 0 90)
			(layer "B.SilkS")
			(hide yes)
			(effects
				(font
					(size 1.27 1.27)
				)
				(justify mirror)
			)
		)
		(property "Value" ""
			(at 0 0 90)
			(layer "B.Fab")
			(effects
				(font
					(size 1.27 1.27)
				)
				(justify mirror)
			)
		)
		(duplicate_pad_numbers_are_jumpers no)
		(fp_line
			(start -0.299974 0.150114)
			(end 0.299974 0.150114)
			(stroke
				(width 0.1)
				(type default)
			)
			(layer "B.Fab")
		)
		(fp_line
			(start 0.299974 0.150114)
			(end 0.299974 -0.150114)
			(stroke
				(width 0.1)
				(type default)
			)
			(layer "B.Fab")
		)
		(fp_line
			(start -0.299974 -0.150114)
			(end -0.299974 0.150114)
			(stroke
				(width 0.1)
				(type default)
			)
			(layer "B.Fab")
		)
		(fp_line
			(start 0.299974 -0.150114)
			(end -0.299974 -0.150114)
			(stroke
				(width 0.1)
				(type default)
			)
			(layer "B.Fab")
		)
		(pad "1" smd rect
			(at 0.2667 0 90)
			(size 0.3048 0.381)
			(layers "B.Cu" "B.Mask" "B.Paste")
			(net "P0V9_CPU0_RT_2D")
		)
		(pad "2" smd rect
			(at -0.2667 0 90)
			(size 0.3048 0.381)
			(layers "B.Cu" "B.Mask" "B.Paste")
			(net "GND")
		)
	)
	(footprint ""
		(layer "B.Cu")
		(at 352.247454 -253.43231)
		(property "Reference" "C2582"
			(at 0 0 0)
			(layer "B.SilkS")
			(hide yes)
			(effects
				(font
					(size 1.27 1.27)
				)
				(justify mirror)
			)
		)
		(property "Value" ""
			(at 0 0 0)
			(layer "B.Fab")
			(effects
				(font
					(size 1.27 1.27)
				)
				(justify mirror)
			)
		)
		(duplicate_pad_numbers_are_jumpers no)
		(fp_line
			(start -0.7874 -0.4064)
			(end -0.7874 0.4064)
			(stroke
				(width 0.1524)
				(type default)
			)
			(layer "B.SilkS")
		)
		(fp_line
			(start -0.7874 0.4064)
			(end 0.7874 0.4064)
			(stroke
				(width 0.1524)
				(type default)
			)
			(layer "B.SilkS")
		)
		(fp_line
			(start 0.7874 -0.4064)
			(end -0.7874 -0.4064)
			(stroke
				(width 0.1524)
				(type default)
			)
			(layer "B.SilkS")
		)
		(fp_line
			(start 0.7874 0.4064)
			(end 0.7874 -0.4064)
			(stroke
				(width 0.1524)
				(type default)
			)
			(layer "B.SilkS")
		)
		(fp_line
			(start -0.67945 -0.3048)
			(end -0.67945 0.3048)
			(stroke
				(width 0.1)
				(type default)
			)
			(layer "B.Fab")
		)
		(fp_line
			(start -0.67945 0.3048)
			(end -0.120396 0.3048)
			(stroke
				(width 0.1)
				(type default)
			)
			(layer "B.Fab")
		)
		(fp_line
			(start -0.12065 -0.3048)
			(end -0.67945 -0.3048)
			(stroke
				(width 0.1)
				(type default)
			)
			(layer "B.Fab")
		)
		(fp_line
			(start -0.12065 -0.2794)
			(end -0.12065 -0.3048)
			(stroke
				(width 0.1)
				(type default)
			)
			(layer "B.Fab")
		)
		(fp_line
			(start -0.120396 0.2794)
			(end 0.12065 0.2794)
			(stroke
				(width 0.1)
				(type default)
			)
			(layer "B.Fab")
		)
		(fp_line
			(start -0.120396 0.3048)
			(end -0.120396 0.2794)
			(stroke
				(width 0.1)
				(type default)
			)
			(layer "B.Fab")
		)
		(fp_line
			(start 0.12065 -0.305054)
			(end 0.12065 -0.2794)
			(stroke
				(width 0.1)
				(type default)
			)
			(layer "B.Fab")
		)
		(fp_line
			(start 0.12065 -0.2794)
			(end -0.12065 -0.2794)
			(stroke
				(width 0.1)
				(type default)
			)
			(layer "B.Fab")
		)
		(fp_line
			(start 0.12065 0.2794)
			(end 0.12065 0.3048)
			(stroke
				(width 0.1)
				(type default)
			)
			(layer "B.Fab")
		)
		(fp_line
			(start 0.12065 0.3048)
			(end 0.67945 0.3048)
			(stroke
				(width 0.1)
				(type default)
			)
			(layer "B.Fab")
		)
		(fp_line
			(start 0.67945 -0.305054)
			(end 0.12065 -0.305054)
			(stroke
				(width 0.1)
				(type default)
			)
			(layer "B.Fab")
		)
		(fp_line
			(start 0.67945 0.3048)
			(end 0.67945 -0.305054)
			(stroke
				(width 0.1)
				(type default)
			)
			(layer "B.Fab")
		)
		(pad "1" smd circle
			(at 0.40005 0 180)
			(size 0 0)
			(layers "B.Cu" "B.Mask" "B.Paste")
			(net "PVDDCR_SOC_P0")
		)
		(pad "2" smd circle
			(at -0.40005 0 180)
			(size 0 0)
			(layers "B.Cu" "B.Mask" "B.Paste")
			(net "GND")
		)
	)
)
